(kicad_pcb
	(version 20260206)
	(generator "pcbnew")
	(generator_version "10.0")
	(general
		(thickness 1.6)
		(legacy_teardrops no)
	)
	(paper "A4")
	(title_block
		(title "03242023_DA0F0TMBIJ0_F0T_Motherboard_J_brd_V01_OCP.brd")
		(comment 1 "Grand Teton / footprints 5211-5216 of 6105")
	)
	(layers
		(0 "F.Cu" signal "TOP")
		(4 "In1.Cu" signal "GND")
		(6 "In2.Cu" signal "IN1")
		(8 "In3.Cu" signal "GND1")
		(10 "In4.Cu" signal "IN2")
		(12 "In5.Cu" signal "GND2")
		(14 "In6.Cu" signal "IN3")
		(16 "In7.Cu" signal "GND3")
		(18 "In8.Cu" signal "VCC")
		(20 "In9.Cu" signal "VCC1")
		(22 "In10.Cu" signal "GND4")
		(24 "In11.Cu" signal "IN4")
		(26 "In12.Cu" signal "GND5")
		(28 "In13.Cu" signal "IN5")
		(30 "In14.Cu" signal "GND6")
		(32 "In15.Cu" signal "IN6")
		(34 "In16.Cu" signal "GND7")
		(2 "B.Cu" signal "BOTTOM")
		(9 "F.Adhes" user "F.Adhesive")
		(11 "B.Adhes" user "B.Adhesive")
		(13 "F.Paste" user "Package Geometry/Pastemask Top")
		(15 "B.Paste" user "Package Geometry/Pastemask Bottom")
		(5 "F.SilkS" user "Ref Des/Silkscreen Top")
		(7 "B.SilkS" user "Ref Des/Silkscreen Bottom")
		(1 "F.Mask" user "Board Geometry/Soldermask Top")
		(3 "B.Mask" user "Board Geometry/Soldermask Bottom")
		(17 "Dwgs.User" user "User.Drawings")
		(19 "Cmts.User" user "User.Comments")
		(21 "Eco1.User" user "User.Eco1")
		(23 "Eco2.User" user "User.Eco2")
		(25 "Edge.Cuts" user "Board Geometry/Outline")
		(27 "Margin" user)
		(31 "F.CrtYd" user "Package Geometry/Place Bound Top")
		(29 "B.CrtYd" user "Package Geometry/Place Bound Bottom")
		(35 "F.Fab" user "Ref Des/Assembly Top")
		(33 "B.Fab" user "Ref Des/Assembly Bottom")
	)
	(footprint ""
		(layer "B.Cu")
		(at 323.661278 -188.48451 90)
		(property "Reference" "R302"
			(at 0 0 90)
			(layer "B.SilkS")
			(hide yes)
			(effects
				(font
					(size 1.27 1.27)
				)
				(justify mirror)
			)
		)
		(property "Value" ""
			(at 0 0 90)
			(layer "B.Fab")
			(effects
				(font
					(size 1.27 1.27)
				)
				(justify mirror)
			)
		)
		(duplicate_pad_numbers_are_jumpers no)
		(fp_line
			(start 0.7874 -0.4064)
			(end -0.7874 -0.4064)
			(stroke
				(width 0.1524)
				(type default)
			)
			(layer "B.SilkS")
		)
		(fp_line
			(start -0.7874 -0.4064)
			(end -0.7874 0.4064)
			(stroke
				(width 0.1524)
				(type default)
			)
			(layer "B.SilkS")
		)
		(fp_line
			(start 0.7874 0.4064)
			(end 0.7874 -0.4064)
			(stroke
				(width 0.1524)
				(type default)
			)
			(layer "B.SilkS")
		)
		(fp_line
			(start -0.7874 0.4064)
			(end 0.7874 0.4064)
			(stroke
				(width 0.1524)
				(type default)
			)
			(layer "B.SilkS")
		)
		(fp_line
			(start 0.67945 -0.305054)
			(end 0.12065 -0.305054)
			(stroke
				(width 0.1)
				(type default)
			)
			(layer "B.Fab")
		)
		(fp_line
			(start 0.12065 -0.305054)
			(end 0.12065 -0.2794)
			(stroke
				(width 0.1)
				(type default)
			)
			(layer "B.Fab")
		)
		(fp_line
			(start -0.12065 -0.3048)
			(end -0.67945 -0.3048)
			(stroke
				(width 0.1)
				(type default)
			)
			(layer "B.Fab")
		)
		(fp_line
			(start -0.67945 -0.3048)
			(end -0.67945 0.3048)
			(stroke
				(width 0.1)
				(type default)
			)
			(layer "B.Fab")
		)
		(fp_line
			(start 0.12065 -0.2794)
			(end -0.12065 -0.2794)
			(stroke
				(width 0.1)
				(type default)
			)
			(layer "B.Fab")
		)
		(fp_line
			(start -0.12065 -0.2794)
			(end -0.12065 -0.3048)
			(stroke
				(width 0.1)
				(type default)
			)
			(layer "B.Fab")
		)
		(fp_line
			(start 0.12065 0.2794)
			(end 0.12065 0.3048)
			(stroke
				(width 0.1)
				(type default)
			)
			(layer "B.Fab")
		)
		(fp_line
			(start -0.120396 0.2794)
			(end 0.12065 0.2794)
			(stroke
				(width 0.1)
				(type default)
			)
			(layer "B.Fab")
		)
		(fp_line
			(start 0.67945 0.3048)
			(end 0.67945 -0.305054)
			(stroke
				(width 0.1)
				(type default)
			)
			(layer "B.Fab")
		)
		(fp_line
			(start 0.12065 0.3048)
			(end 0.67945 0.3048)
			(stroke
				(width 0.1)
				(type default)
			)
			(layer "B.Fab")
		)
		(fp_line
			(start -0.120396 0.3048)
			(end -0.120396 0.2794)
			(stroke
				(width 0.1)
				(type default)
			)
			(layer "B.Fab")
		)
		(fp_line
			(start -0.67945 0.3048)
			(end -0.120396 0.3048)
			(stroke
				(width 0.1)
				(type default)
			)
			(layer "B.Fab")
		)
		(pad "1" smd circle
			(at 0.40005 0 270)
			(size 0 0)
			(layers "B.Cu" "B.Mask" "B.Paste")
			(net "H_CPU0_RMCA_LVC1_R_N")
		)
		(pad "2" smd circle
			(at -0.40005 0 270)
			(size 0 0)
			(layers "B.Cu" "B.Mask" "B.Paste")
			(net "H_CPU_RMCA_LVC1_R_N")
		)
	)
	(footprint ""
		(layer "B.Cu")
		(at 333.786988 -44.962064)
		(property "Reference" "C1206"
			(at 0 0 0)
			(layer "B.SilkS")
			(hide yes)
			(effects
				(font
					(size 1.27 1.27)
				)
				(justify mirror)
			)
		)
		(property "Value" ""
			(at 0 0 0)
			(layer "B.Fab")
			(effects
				(font
					(size 1.27 1.27)
				)
				(justify mirror)
			)
		)
		(duplicate_pad_numbers_are_jumpers no)
		(fp_line
			(start -0.7874 -0.4064)
			(end -0.7874 0.4064)
			(stroke
				(width 0.1524)
				(type default)
			)
			(layer "B.SilkS")
		)
		(fp_line
			(start -0.7874 0.4064)
			(end 0.7874 0.4064)
			(stroke
				(width 0.1524)
				(type default)
			)
			(layer "B.SilkS")
		)
		(fp_line
			(start 0.7874 -0.4064)
			(end -0.7874 -0.4064)
			(stroke
				(width 0.1524)
				(type default)
			)
			(layer "B.SilkS")
		)
		(fp_line
			(start 0.7874 0.4064)
			(end 0.7874 -0.4064)
			(stroke
				(width 0.1524)
				(type default)
			)
			(layer "B.SilkS")
		)
		(fp_line
			(start -0.67945 -0.3048)
			(end -0.67945 0.3048)
			(stroke
				(width 0.1)
				(type default)
			)
			(layer "B.Fab")
		)
		(fp_line
			(start -0.67945 0.3048)
			(end -0.120396 0.3048)
			(stroke
				(width 0.1)
				(type default)
			)
			(layer "B.Fab")
		)
		(fp_line
			(start -0.12065 -0.3048)
			(end -0.67945 -0.3048)
			(stroke
				(width 0.1)
				(type default)
			)
			(layer "B.Fab")
		)
		(fp_line
			(start -0.12065 -0.2794)
			(end -0.12065 -0.3048)
			(stroke
				(width 0.1)
				(type default)
			)
			(layer "B.Fab")
		)
		(fp_line
			(start -0.120396 0.2794)
			(end 0.12065 0.2794)
			(stroke
				(width 0.1)
				(type default)
			)
			(layer "B.Fab")
		)
		(fp_line
			(start -0.120396 0.3048)
			(end -0.120396 0.2794)
			(stroke
				(width 0.1)
				(type default)
			)
			(layer "B.Fab")
		)
		(fp_line
			(start 0.12065 -0.305054)
			(end 0.12065 -0.2794)
			(stroke
				(width 0.1)
				(type default)
			)
			(layer "B.Fab")
		)
		(fp_line
			(start 0.12065 -0.2794)
			(end -0.12065 -0.2794)
			(stroke
				(width 0.1)
				(type default)
			)
			(layer "B.Fab")
		)
		(fp_line
			(start 0.12065 0.2794)
			(end 0.12065 0.3048)
			(stroke
				(width 0.1)
				(type default)
			)
			(layer "B.Fab")
		)
		(fp_line
			(start 0.12065 0.3048)
			(end 0.67945 0.3048)
			(stroke
				(width 0.1)
				(type default)
			)
			(layer "B.Fab")
		)
		(fp_line
			(start 0.67945 -0.305054)
			(end 0.12065 -0.305054)
			(stroke
				(width 0.1)
				(type default)
			)
			(layer "B.Fab")
		)
		(fp_line
			(start 0.67945 0.3048)
			(end 0.67945 -0.305054)
			(stroke
				(width 0.1)
				(type default)
			)
			(layer "B.Fab")
		)
		(pad "1" smd circle
			(at 0.40005 0 180)
			(size 0 0)
			(layers "B.Cu" "B.Mask" "B.Paste")
			(net "P3V3_AUX")
		)
		(pad "2" smd circle
			(at -0.40005 0 180)
			(size 0 0)
			(layers "B.Cu" "B.Mask" "B.Paste")
			(net "GND")
		)
	)
	(footprint ""
		(layer "B.Cu")
		(at 293.764208 -354.02139 -90)
		(property "Reference" "PC1183_P0_4"
			(at 0 0 90)
			(layer "B.SilkS")
			(hide yes)
			(effects
				(font
					(size 1.27 1.27)
				)
				(justify mirror)
			)
		)
		(property "Value" ""
			(at 0 0 90)
			(layer "B.Fab")
			(effects
				(font
					(size 1.27 1.27)
				)
				(justify mirror)
			)
		)
		(duplicate_pad_numbers_are_jumpers no)
		(fp_line
			(start -0.7874 0.4064)
			(end 0.7874 0.4064)
			(stroke
				(width 0.1524)
				(type default)
			)
			(layer "B.SilkS")
		)
		(fp_line
			(start 0.7874 0.4064)
			(end 0.7874 -0.4064)
			(stroke
				(width 0.1524)
				(type default)
			)
			(layer "B.SilkS")
		)
		(fp_line
			(start -0.7874 -0.4064)
			(end -0.7874 0.4064)
			(stroke
				(width 0.1524)
				(type default)
			)
			(layer "B.SilkS")
		)
		(fp_line
			(start 0.7874 -0.4064)
			(end -0.7874 -0.4064)
			(stroke
				(width 0.1524)
				(type default)
			)
			(layer "B.SilkS")
		)
		(fp_line
			(start -0.67945 0.3048)
			(end -0.120396 0.3048)
			(stroke
				(width 0.1)
				(type default)
			)
			(layer "B.Fab")
		)
		(fp_line
			(start -0.120396 0.3048)
			(end -0.120396 0.2794)
			(stroke
				(width 0.1)
				(type default)
			)
			(layer "B.Fab")
		)
		(fp_line
			(start 0.12065 0.3048)
			(end 0.67945 0.3048)
			(stroke
				(width 0.1)
				(type default)
			)
			(layer "B.Fab")
		)
		(fp_line
			(start 0.67945 0.3048)
			(end 0.67945 -0.305054)
			(stroke
				(width 0.1)
				(type default)
			)
			(layer "B.Fab")
		)
		(fp_line
			(start -0.120396 0.2794)
			(end 0.12065 0.2794)
			(stroke
				(width 0.1)
				(type default)
			)
			(layer "B.Fab")
		)
		(fp_line
			(start 0.12065 0.2794)
			(end 0.12065 0.3048)
			(stroke
				(width 0.1)
				(type default)
			)
			(layer "B.Fab")
		)
		(fp_line
			(start -0.12065 -0.2794)
			(end -0.12065 -0.3048)
			(stroke
				(width 0.1)
				(type default)
			)
			(layer "B.Fab")
		)
		(fp_line
			(start 0.12065 -0.2794)
			(end -0.12065 -0.2794)
			(stroke
				(width 0.1)
				(type default)
			)
			(layer "B.Fab")
		)
		(fp_line
			(start -0.67945 -0.3048)
			(end -0.67945 0.3048)
			(stroke
				(width 0.1)
				(type default)
			)
			(layer "B.Fab")
		)
		(fp_line
			(start -0.12065 -0.3048)
			(end -0.67945 -0.3048)
			(stroke
				(width 0.1)
				(type default)
			)
			(layer "B.Fab")
		)
		(fp_line
			(start 0.12065 -0.305054)
			(end 0.12065 -0.2794)
			(stroke
				(width 0.1)
				(type default)
			)
			(layer "B.Fab")
		)
		(fp_line
			(start 0.67945 -0.305054)
			(end 0.12065 -0.305054)
			(stroke
				(width 0.1)
				(type default)
			)
			(layer "B.Fab")
		)
		(pad "1" smd circle
			(at 0.40005 0 90)
			(size 0 0)
			(layers "B.Cu" "B.Mask" "B.Paste")
			(net "PVCCFA_EHV_FIVRA_CPU0")
		)
		(pad "2" smd circle
			(at -0.40005 0 90)
			(size 0 0)
			(layers "B.Cu" "B.Mask" "B.Paste")
			(net "GND")
		)
	)
	(footprint ""
		(layer "B.Cu")
		(at 187.88888 -102.707948 180)
		(property "Reference" "C1944"
			(at 0 0 0)
			(layer "B.SilkS")
			(hide yes)
			(effects
				(font
					(size 1.27 1.27)
				)
				(justify mirror)
			)
		)
		(property "Value" ""
			(at 0 0 0)
			(layer "B.Fab")
			(effects
				(font
					(size 1.27 1.27)
				)
				(justify mirror)
			)
		)
		(duplicate_pad_numbers_are_jumpers no)
		(fp_line
			(start 0.7874 0.4064)
			(end 0.7874 -0.4064)
			(stroke
				(width 0.1524)
				(type default)
			)
			(layer "B.SilkS")
		)
		(fp_line
			(start 0.7874 -0.4064)
			(end -0.7874 -0.4064)
			(stroke
				(width 0.1524)
				(type default)
			)
			(layer "B.SilkS")
		)
		(fp_line
			(start -0.7874 0.4064)
			(end 0.7874 0.4064)
			(stroke
				(width 0.1524)
				(type default)
			)
			(layer "B.SilkS")
		)
		(fp_line
			(start -0.7874 -0.4064)
			(end -0.7874 0.4064)
			(stroke
				(width 0.1524)
				(type default)
			)
			(layer "B.SilkS")
		)
		(fp_line
			(start 0.67945 0.3048)
			(end 0.67945 -0.305054)
			(stroke
				(width 0.1)
				(type default)
			)
			(layer "B.Fab")
		)
		(fp_line
			(start 0.67945 -0.305054)
			(end 0.12065 -0.305054)
			(stroke
				(width 0.1)
				(type default)
			)
			(layer "B.Fab")
		)
		(fp_line
			(start 0.12065 0.3048)
			(end 0.67945 0.3048)
			(stroke
				(width 0.1)
				(type default)
			)
			(layer "B.Fab")
		)
		(fp_line
			(start 0.12065 0.2794)
			(end 0.12065 0.3048)
			(stroke
				(width 0.1)
				(type default)
			)
			(layer "B.Fab")
		)
		(fp_line
			(start 0.12065 -0.2794)
			(end -0.12065 -0.2794)
			(stroke
				(width 0.1)
				(type default)
			)
			(layer "B.Fab")
		)
		(fp_line
			(start 0.12065 -0.305054)
			(end 0.12065 -0.2794)
			(stroke
				(width 0.1)
				(type default)
			)
			(layer "B.Fab")
		)
		(fp_line
			(start -0.120396 0.3048)
			(end -0.120396 0.2794)
			(stroke
				(width 0.1)
				(type default)
			)
			(layer "B.Fab")
		)
		(fp_line
			(start -0.120396 0.2794)
			(end 0.12065 0.2794)
			(stroke
				(width 0.1)
				(type default)
			)
			(layer "B.Fab")
		)
		(fp_line
			(start -0.12065 -0.2794)
			(end -0.12065 -0.3048)
			(stroke
				(width 0.1)
				(type default)
			)
			(layer "B.Fab")
		)
		(fp_line
			(start -0.12065 -0.3048)
			(end -0.67945 -0.3048)
			(stroke
				(width 0.1)
				(type default)
			)
			(layer "B.Fab")
		)
		(fp_line
			(start -0.67945 0.3048)
			(end -0.120396 0.3048)
			(stroke
				(width 0.1)
				(type default)
			)
			(layer "B.Fab")
		)
		(fp_line
			(start -0.67945 -0.3048)
			(end -0.67945 0.3048)
			(stroke
				(width 0.1)
				(type default)
			)
			(layer "B.Fab")
		)
		(pad "1" smd circle
			(at 0.40005 0)
			(size 0 0)
			(layers "B.Cu" "B.Mask" "B.Paste")
			(net "P3V3_AUX_FPGA_VCCIO2")
		)
		(pad "2" smd circle
			(at -0.40005 0)
			(size 0 0)
			(layers "B.Cu" "B.Mask" "B.Paste")
			(net "GND")
		)
	)
	(footprint ""
		(layer "B.Cu")
		(at 178.803554 -354.565204 -90)
		(property "Reference" "PR1306"
			(at 0 0 90)
			(layer "B.SilkS")
			(hide yes)
			(effects
				(font
					(size 1.27 1.27)
				)
				(justify mirror)
			)
		)
		(property "Value" ""
			(at 0 0 90)
			(layer "B.Fab")
			(effects
				(font
					(size 1.27 1.27)
				)
				(justify mirror)
			)
		)
		(duplicate_pad_numbers_are_jumpers no)
		(fp_line
			(start -0.7874 0.4064)
			(end 0.7874 0.4064)
			(stroke
				(width 0.1524)
				(type default)
			)
			(layer "B.SilkS")
		)
		(fp_line
			(start 0.7874 0.4064)
			(end 0.7874 -0.4064)
			(stroke
				(width 0.1524)
				(type default)
			)
			(layer "B.SilkS")
		)
		(fp_line
			(start -0.7874 -0.4064)
			(end -0.7874 0.4064)
			(stroke
				(width 0.1524)
				(type default)
			)
			(layer "B.SilkS")
		)
		(fp_line
			(start 0.7874 -0.4064)
			(end -0.7874 -0.4064)
			(stroke
				(width 0.1524)
				(type default)
			)
			(layer "B.SilkS")
		)
		(fp_line
			(start -0.67945 0.3048)
			(end -0.120396 0.3048)
			(stroke
				(width 0.1)
				(type default)
			)
			(layer "B.Fab")
		)
		(fp_line
			(start -0.120396 0.3048)
			(end -0.120396 0.2794)
			(stroke
				(width 0.1)
				(type default)
			)
			(layer "B.Fab")
		)
		(fp_line
			(start 0.12065 0.3048)
			(end 0.67945 0.3048)
			(stroke
				(width 0.1)
				(type default)
			)
			(layer "B.Fab")
		)
		(fp_line
			(start 0.67945 0.3048)
			(end 0.67945 -0.305054)
			(stroke
				(width 0.1)
				(type default)
			)
			(layer "B.Fab")
		)
		(fp_line
			(start -0.120396 0.2794)
			(end 0.12065 0.2794)
			(stroke
				(width 0.1)
				(type default)
			)
			(layer "B.Fab")
		)
		(fp_line
			(start 0.12065 0.2794)
			(end 0.12065 0.3048)
			(stroke
				(width 0.1)
				(type default)
			)
			(layer "B.Fab")
		)
		(fp_line
			(start -0.12065 -0.2794)
			(end -0.12065 -0.3048)
			(stroke
				(width 0.1)
				(type default)
			)
			(layer "B.Fab")
		)
		(fp_line
			(start 0.12065 -0.2794)
			(end -0.12065 -0.2794)
			(stroke
				(width 0.1)
				(type default)
			)
			(layer "B.Fab")
		)
		(fp_line
			(start -0.67945 -0.3048)
			(end -0.67945 0.3048)
			(stroke
				(width 0.1)
				(type default)
			)
			(layer "B.Fab")
		)
		(fp_line
			(start -0.12065 -0.3048)
			(end -0.67945 -0.3048)
			(stroke
				(width 0.1)
				(type default)
			)
			(layer "B.Fab")
		)
		(fp_line
			(start 0.12065 -0.305054)
			(end 0.12065 -0.2794)
			(stroke
				(width 0.1)
				(type default)
			)
			(layer "B.Fab")
		)
		(fp_line
			(start 0.67945 -0.305054)
			(end 0.12065 -0.305054)
			(stroke
				(width 0.1)
				(type default)
			)
			(layer "B.Fab")
		)
		(pad "1" smd circle
			(at 0.40005 0 90)
			(size 0 0)
			(layers "B.Cu" "B.Mask" "B.Paste")
			(net "PVCCFA_EHV_FIVRA_CPU1_PVCC1")
		)
		(pad "2" smd circle
			(at -0.40005 0 90)
			(size 0 0)
			(layers "B.Cu" "B.Mask" "B.Paste")
			(net "PVCCFA_EHV_FIVRA_CPU1_VDD3")
		)
	)
	(footprint ""
		(layer "B.Cu")
		(at 157.02788 -113.756948 180)
		(property "Reference" "R1681"
			(at 0 0 0)
			(layer "B.SilkS")
			(hide yes)
			(effects
				(font
					(size 1.27 1.27)
				)
				(justify mirror)
			)
		)
		(property "Value" ""
			(at 0 0 0)
			(layer "B.Fab")
			(effects
				(font
					(size 1.27 1.27)
				)
				(justify mirror)
			)
		)
		(duplicate_pad_numbers_are_jumpers no)
		(fp_line
			(start 0.7874 0.4064)
			(end 0.7874 -0.4064)
			(stroke
				(width 0.1524)
				(type default)
			)
			(layer "B.SilkS")
		)
		(fp_line
			(start 0.7874 -0.4064)
			(end -0.7874 -0.4064)
			(stroke
				(width 0.1524)
				(type default)
			)
			(layer "B.SilkS")
		)
		(fp_line
			(start -0.7874 0.4064)
			(end 0.7874 0.4064)
			(stroke
				(width 0.1524)
				(type default)
			)
			(layer "B.SilkS")
		)
		(fp_line
			(start -0.7874 -0.4064)
			(end -0.7874 0.4064)
			(stroke
				(width 0.1524)
				(type default)
			)
			(layer "B.SilkS")
		)
		(fp_line
			(start 0.67945 0.3048)
			(end 0.67945 -0.305054)
			(stroke
				(width 0.1)
				(type default)
			)
			(layer "B.Fab")
		)
		(fp_line
			(start 0.67945 -0.305054)
			(end 0.12065 -0.305054)
			(stroke
				(width 0.1)
				(type default)
			)
			(layer "B.Fab")
		)
		(fp_line
			(start 0.12065 0.3048)
			(end 0.67945 0.3048)
			(stroke
				(width 0.1)
				(type default)
			)
			(layer "B.Fab")
		)
		(fp_line
			(start 0.12065 0.2794)
			(end 0.12065 0.3048)
			(stroke
				(width 0.1)
				(type default)
			)
			(layer "B.Fab")
		)
		(fp_line
			(start 0.12065 -0.2794)
			(end -0.12065 -0.2794)
			(stroke
				(width 0.1)
				(type default)
			)
			(layer "B.Fab")
		)
		(fp_line
			(start 0.12065 -0.305054)
			(end 0.12065 -0.2794)
			(stroke
				(width 0.1)
				(type default)
			)
			(layer "B.Fab")
		)
		(fp_line
			(start -0.120396 0.3048)
			(end -0.120396 0.2794)
			(stroke
				(width 0.1)
				(type default)
			)
			(layer "B.Fab")
		)
		(fp_line
			(start -0.120396 0.2794)
			(end 0.12065 0.2794)
			(stroke
				(width 0.1)
				(type default)
			)
			(layer "B.Fab")
		)
		(fp_line
			(start -0.12065 -0.2794)
			(end -0.12065 -0.3048)
			(stroke
				(width 0.1)
				(type default)
			)
			(layer "B.Fab")
		)
		(fp_line
			(start -0.12065 -0.3048)
			(end -0.67945 -0.3048)
			(stroke
				(width 0.1)
				(type default)
			)
			(layer "B.Fab")
		)
		(fp_line
			(start -0.67945 0.3048)
			(end -0.120396 0.3048)
			(stroke
				(width 0.1)
				(type default)
			)
			(layer "B.Fab")
		)
		(fp_line
			(start -0.67945 -0.3048)
			(end -0.67945 0.3048)
			(stroke
				(width 0.1)
				(type default)
			)
			(layer "B.Fab")
		)
		(pad "1" smd circle
			(at 0.40005 0)
			(size 0 0)
			(layers "B.Cu" "B.Mask" "B.Paste")
			(net "P3V3_AUX")
		)
		(pad "2" smd circle
			(at -0.40005 0)
			(size 0 0)
			(layers "B.Cu" "B.Mask" "B.Paste")
			(net "PU_RST_DEDI_BUSY_PLD_N")
		)
	)
)
